(kicad_pcb
	(version 20260206)
	(generator "pcbnew")
	(generator_version "10.0")
	(general
		(thickness 1.6)
		(legacy_teardrops no)
	)
	(paper "A4")
	(title_block
		(title "04192023_DAF0TMB3IC0_F0TG_MB_C_brd_V02_OCP.brd")
		(comment 1 "Grand Teton / footprints 4293-4301 of 8354")
	)
	(layers
		(0 "F.Cu" signal "TOP")
		(4 "In1.Cu" signal "GND")
		(6 "In2.Cu" signal "IN1")
		(8 "In3.Cu" signal "GND1")
		(10 "In4.Cu" signal "IN2")
		(12 "In5.Cu" signal "GND2")
		(14 "In6.Cu" signal "IN3")
		(16 "In7.Cu" signal "GND3")
		(18 "In8.Cu" signal "VCC")
		(20 "In9.Cu" signal "VCC1")
		(22 "In10.Cu" signal "GND4")
		(24 "In11.Cu" signal "IN4")
		(26 "In12.Cu" signal "GND5")
		(28 "In13.Cu" signal "IN5")
		(30 "In14.Cu" signal "GND6")
		(32 "In15.Cu" signal "IN6")
		(34 "In16.Cu" signal "GND7")
		(2 "B.Cu" signal "BOTTOM")
		(9 "F.Adhes" user "F.Adhesive")
		(11 "B.Adhes" user "B.Adhesive")
		(13 "F.Paste" user "Package Geometry/Pastemask Top")
		(15 "B.Paste" user "Package Geometry/Pastemask Bottom")
		(5 "F.SilkS" user "Ref Des/Silkscreen Top")
		(7 "B.SilkS" user "Ref Des/Silkscreen Bottom")
		(1 "F.Mask" user "Board Geometry/Soldermask Top")
		(3 "B.Mask" user "Board Geometry/Soldermask Bottom")
		(17 "Dwgs.User" user "User.Drawings")
		(19 "Cmts.User" user "User.Comments")
		(21 "Eco1.User" user "User.Eco1")
		(23 "Eco2.User" user "User.Eco2")
		(25 "Edge.Cuts" user "Board Geometry/Outline")
		(27 "Margin" user)
		(31 "F.CrtYd" user "Package Geometry/Place Bound Top")
		(29 "B.CrtYd" user "Package Geometry/Place Bound Bottom")
		(35 "F.Fab" user "Ref Des/Assembly Top")
		(33 "B.Fab" user "Ref Des/Assembly Bottom")
	)
	(footprint ""
		(layer "F.Cu")
		(at 33.187132 -343.716864 180)
		(property "Reference" "PC177"
			(at 0 0 180)
			(layer "F.SilkS")
			(hide yes)
			(effects
				(font
					(size 1.27 1.27)
				)
			)
		)
		(property "Value" ""
			(at 0 0 180)
			(layer "F.Fab")
			(effects
				(font
					(size 1.27 1.27)
				)
			)
		)
		(duplicate_pad_numbers_are_jumpers no)
		(fp_line
			(start 0.7874 0.4064)
			(end -0.7874 0.4064)
			(stroke
				(width 0.1524)
				(type default)
			)
			(layer "F.SilkS")
		)
		(fp_line
			(start 0.7874 -0.4064)
			(end 0.7874 0.4064)
			(stroke
				(width 0.1524)
				(type default)
			)
			(layer "F.SilkS")
		)
		(fp_line
			(start -0.7874 0.4064)
			(end -0.7874 -0.4064)
			(stroke
				(width 0.1524)
				(type default)
			)
			(layer "F.SilkS")
		)
		(fp_line
			(start -0.7874 -0.4064)
			(end 0.7874 -0.4064)
			(stroke
				(width 0.1524)
				(type default)
			)
			(layer "F.SilkS")
		)
		(fp_line
			(start 0.67945 0.3048)
			(end 0.120396 0.3048)
			(stroke
				(width 0.1)
				(type default)
			)
			(layer "F.Fab")
		)
		(fp_line
			(start 0.67945 -0.3048)
			(end 0.67945 0.3048)
			(stroke
				(width 0.1)
				(type default)
			)
			(layer "F.Fab")
		)
		(fp_line
			(start 0.12065 -0.2794)
			(end 0.12065 -0.3048)
			(stroke
				(width 0.1)
				(type default)
			)
			(layer "F.Fab")
		)
		(fp_line
			(start 0.12065 -0.3048)
			(end 0.67945 -0.3048)
			(stroke
				(width 0.1)
				(type default)
			)
			(layer "F.Fab")
		)
		(fp_line
			(start 0.120396 0.3048)
			(end 0.120396 0.2794)
			(stroke
				(width 0.1)
				(type default)
			)
			(layer "F.Fab")
		)
		(fp_line
			(start 0.120396 0.2794)
			(end -0.12065 0.2794)
			(stroke
				(width 0.1)
				(type default)
			)
			(layer "F.Fab")
		)
		(fp_line
			(start -0.12065 0.3048)
			(end -0.67945 0.3048)
			(stroke
				(width 0.1)
				(type default)
			)
			(layer "F.Fab")
		)
		(fp_line
			(start -0.12065 0.2794)
			(end -0.12065 0.3048)
			(stroke
				(width 0.1)
				(type default)
			)
			(layer "F.Fab")
		)
		(fp_line
			(start -0.12065 -0.2794)
			(end 0.12065 -0.2794)
			(stroke
				(width 0.1)
				(type default)
			)
			(layer "F.Fab")
		)
		(fp_line
			(start -0.12065 -0.305054)
			(end -0.12065 -0.2794)
			(stroke
				(width 0.1)
				(type default)
			)
			(layer "F.Fab")
		)
		(fp_line
			(start -0.67945 0.3048)
			(end -0.67945 -0.305054)
			(stroke
				(width 0.1)
				(type default)
			)
			(layer "F.Fab")
		)
		(fp_line
			(start -0.67945 -0.305054)
			(end -0.12065 -0.305054)
			(stroke
				(width 0.1)
				(type default)
			)
			(layer "F.Fab")
		)
		(pad "1" smd circle
			(at -0.40005 0 180)
			(size 0 0)
			(layers "F.Cu" "F.Mask" "F.Paste")
			(net "SW_PVDDIO_P1_SW3")
		)
		(pad "2" smd circle
			(at 0.40005 0 180)
			(size 0 0)
			(layers "F.Cu" "F.Mask" "F.Paste")
			(net "SW_PVDDIO_P1_SW3_RC")
		)
	)
	(footprint ""
		(layer "F.Cu")
		(at 135.36168 -29.01442 -90)
		(property "Reference" "R6195"
			(at 0 0 270)
			(layer "F.SilkS")
			(hide yes)
			(effects
				(font
					(size 1.27 1.27)
				)
			)
		)
		(property "Value" ""
			(at 0 0 270)
			(layer "F.Fab")
			(effects
				(font
					(size 1.27 1.27)
				)
			)
		)
		(duplicate_pad_numbers_are_jumpers no)
		(fp_line
			(start -0.32512 0.175006)
			(end -0.32512 -0.175006)
			(stroke
				(width 0.1)
				(type default)
			)
			(layer "F.Fab")
		)
		(fp_line
			(start 0.32512 0.175006)
			(end -0.32512 0.175006)
			(stroke
				(width 0.1)
				(type default)
			)
			(layer "F.Fab")
		)
		(fp_line
			(start -0.32512 -0.175006)
			(end 0.32512 -0.175006)
			(stroke
				(width 0.1)
				(type default)
			)
			(layer "F.Fab")
		)
		(fp_line
			(start 0.32512 -0.175006)
			(end 0.32512 0.175006)
			(stroke
				(width 0.1)
				(type default)
			)
			(layer "F.Fab")
		)
		(pad "1" smd rect
			(at -0.2667 0 270)
			(size 0.3048 0.381)
			(layers "F.Cu" "F.Mask" "F.Paste")
			(net "USB2_CPU0_P0_HUB1_R_DN")
		)
		(pad "2" smd rect
			(at 0.2667 0 90)
			(size 0.3048 0.381)
			(layers "F.Cu" "F.Mask" "F.Paste")
			(net "USB2_HUB_EXT_DN")
		)
	)
	(footprint ""
		(layer "F.Cu")
		(at 10.339832 -160.499806)
		(property "Reference" "H88"
			(at -4.6863 -5.71119 0)
			(unlocked yes)
			(layer "F.SilkS")
			(effects
				(font
					(size 0.7874 0.5842)
					(thickness 0.1524)
				)
				(justify left)
			)
		)
		(property "Value" ""
			(at 0 0 0)
			(layer "F.Fab")
			(effects
				(font
					(size 1.27 1.27)
				)
			)
		)
		(duplicate_pad_numbers_are_jumpers no)
		(pad "1" thru_hole circle
			(at 0 0)
			(size 10.0076 10.0076)
			(drill 5.6134)
			(layers "*.Cu" "*.Mask")
			(remove_unused_layers no)
			(net "GND")
			(clearance -1.9431)
		)
	)
	(footprint ""
		(layer "F.Cu")
		(at 138.016234 -151.619712 -90)
		(property "Reference" "PR335"
			(at 0 0 270)
			(layer "F.SilkS")
			(hide yes)
			(effects
				(font
					(size 1.27 1.27)
				)
			)
		)
		(property "Value" ""
			(at 0 0 270)
			(layer "F.Fab")
			(effects
				(font
					(size 1.27 1.27)
				)
			)
		)
		(duplicate_pad_numbers_are_jumpers no)
		(fp_line
			(start -0.7874 0.4064)
			(end -0.7874 -0.4064)
			(stroke
				(width 0.1524)
				(type default)
			)
			(layer "F.SilkS")
		)
		(fp_line
			(start 0.7874 0.4064)
			(end -0.7874 0.4064)
			(stroke
				(width 0.1524)
				(type default)
			)
			(layer "F.SilkS")
		)
		(fp_line
			(start -0.7874 -0.4064)
			(end 0.7874 -0.4064)
			(stroke
				(width 0.1524)
				(type default)
			)
			(layer "F.SilkS")
		)
		(fp_line
			(start 0.7874 -0.4064)
			(end 0.7874 0.4064)
			(stroke
				(width 0.1524)
				(type default)
			)
			(layer "F.SilkS")
		)
		(fp_line
			(start -0.67945 0.3048)
			(end -0.67945 -0.305054)
			(stroke
				(width 0.1)
				(type default)
			)
			(layer "F.Fab")
		)
		(fp_line
			(start -0.12065 0.3048)
			(end -0.67945 0.3048)
			(stroke
				(width 0.1)
				(type default)
			)
			(layer "F.Fab")
		)
		(fp_line
			(start 0.120396 0.3048)
			(end 0.120396 0.2794)
			(stroke
				(width 0.1)
				(type default)
			)
			(layer "F.Fab")
		)
		(fp_line
			(start 0.67945 0.3048)
			(end 0.120396 0.3048)
			(stroke
				(width 0.1)
				(type default)
			)
			(layer "F.Fab")
		)
		(fp_line
			(start -0.12065 0.2794)
			(end -0.12065 0.3048)
			(stroke
				(width 0.1)
				(type default)
			)
			(layer "F.Fab")
		)
		(fp_line
			(start 0.120396 0.2794)
			(end -0.12065 0.2794)
			(stroke
				(width 0.1)
				(type default)
			)
			(layer "F.Fab")
		)
		(fp_line
			(start -0.12065 -0.2794)
			(end 0.12065 -0.2794)
			(stroke
				(width 0.1)
				(type default)
			)
			(layer "F.Fab")
		)
		(fp_line
			(start 0.12065 -0.2794)
			(end 0.12065 -0.3048)
			(stroke
				(width 0.1)
				(type default)
			)
			(layer "F.Fab")
		)
		(fp_line
			(start 0.12065 -0.3048)
			(end 0.67945 -0.3048)
			(stroke
				(width 0.1)
				(type default)
			)
			(layer "F.Fab")
		)
		(fp_line
			(start 0.67945 -0.3048)
			(end 0.67945 0.3048)
			(stroke
				(width 0.1)
				(type default)
			)
			(layer "F.Fab")
		)
		(fp_line
			(start -0.67945 -0.305054)
			(end -0.12065 -0.305054)
			(stroke
				(width 0.1)
				(type default)
			)
			(layer "F.Fab")
		)
		(fp_line
			(start -0.12065 -0.305054)
			(end -0.12065 -0.2794)
			(stroke
				(width 0.1)
				(type default)
			)
			(layer "F.Fab")
		)
		(pad "1" smd circle
			(at -0.40005 0 270)
			(size 0 0)
			(layers "F.Cu" "F.Mask" "F.Paste")
			(net "PVDDCR_CPU0_P1_PVCC")
		)
		(pad "2" smd circle
			(at 0.40005 0 270)
			(size 0 0)
			(layers "F.Cu" "F.Mask" "F.Paste")
			(net "P5V_AUX")
		)
	)
	(footprint ""
		(layer "F.Cu")
		(at 353.451922 -344.586306 -90)
		(property "Reference" "PC117"
			(at 0 0 270)
			(layer "F.SilkS")
			(hide yes)
			(effects
				(font
					(size 1.27 1.27)
				)
			)
		)
		(property "Value" ""
			(at 0 0 270)
			(layer "F.Fab")
			(effects
				(font
					(size 1.27 1.27)
				)
			)
		)
		(duplicate_pad_numbers_are_jumpers no)
		(fp_line
			(start -0.7874 0.4064)
			(end -0.7874 -0.4064)
			(stroke
				(width 0.1524)
				(type default)
			)
			(layer "F.SilkS")
		)
		(fp_line
			(start 0.7874 0.4064)
			(end -0.7874 0.4064)
			(stroke
				(width 0.1524)
				(type default)
			)
			(layer "F.SilkS")
		)
		(fp_line
			(start -0.7874 -0.4064)
			(end 0.7874 -0.4064)
			(stroke
				(width 0.1524)
				(type default)
			)
			(layer "F.SilkS")
		)
		(fp_line
			(start 0.7874 -0.4064)
			(end 0.7874 0.4064)
			(stroke
				(width 0.1524)
				(type default)
			)
			(layer "F.SilkS")
		)
		(fp_line
			(start -0.67945 0.3048)
			(end -0.67945 -0.305054)
			(stroke
				(width 0.1)
				(type default)
			)
			(layer "F.Fab")
		)
		(fp_line
			(start -0.12065 0.3048)
			(end -0.67945 0.3048)
			(stroke
				(width 0.1)
				(type default)
			)
			(layer "F.Fab")
		)
		(fp_line
			(start 0.120396 0.3048)
			(end 0.120396 0.2794)
			(stroke
				(width 0.1)
				(type default)
			)
			(layer "F.Fab")
		)
		(fp_line
			(start 0.67945 0.3048)
			(end 0.120396 0.3048)
			(stroke
				(width 0.1)
				(type default)
			)
			(layer "F.Fab")
		)
		(fp_line
			(start -0.12065 0.2794)
			(end -0.12065 0.3048)
			(stroke
				(width 0.1)
				(type default)
			)
			(layer "F.Fab")
		)
		(fp_line
			(start 0.120396 0.2794)
			(end -0.12065 0.2794)
			(stroke
				(width 0.1)
				(type default)
			)
			(layer "F.Fab")
		)
		(fp_line
			(start -0.12065 -0.2794)
			(end 0.12065 -0.2794)
			(stroke
				(width 0.1)
				(type default)
			)
			(layer "F.Fab")
		)
		(fp_line
			(start 0.12065 -0.2794)
			(end 0.12065 -0.3048)
			(stroke
				(width 0.1)
				(type default)
			)
			(layer "F.Fab")
		)
		(fp_line
			(start 0.12065 -0.3048)
			(end 0.67945 -0.3048)
			(stroke
				(width 0.1)
				(type default)
			)
			(layer "F.Fab")
		)
		(fp_line
			(start 0.67945 -0.3048)
			(end 0.67945 0.3048)
			(stroke
				(width 0.1)
				(type default)
			)
			(layer "F.Fab")
		)
		(fp_line
			(start -0.67945 -0.305054)
			(end -0.12065 -0.305054)
			(stroke
				(width 0.1)
				(type default)
			)
			(layer "F.Fab")
		)
		(fp_line
			(start -0.12065 -0.305054)
			(end -0.12065 -0.2794)
			(stroke
				(width 0.1)
				(type default)
			)
			(layer "F.Fab")
		)
		(pad "1" smd circle
			(at -0.40005 0 270)
			(size 0 0)
			(layers "F.Cu" "F.Mask" "F.Paste")
			(net "SW_PVDDCR_CPU1_P0_BOOT6_R")
		)
		(pad "2" smd circle
			(at 0.40005 0 270)
			(size 0 0)
			(layers "F.Cu" "F.Mask" "F.Paste")
			(net "SW_PVDDCR_CPU1_P0_BOOTR6")
		)
	)
	(footprint ""
		(layer "F.Cu")
		(at 115.783106 -408.517344 -90)
		(property "Reference" "C6693"
			(at 0 0 270)
			(layer "F.SilkS")
			(hide yes)
			(effects
				(font
					(size 1.27 1.27)
				)
			)
		)
		(property "Value" ""
			(at 0 0 270)
			(layer "F.Fab")
			(effects
				(font
					(size 1.27 1.27)
				)
			)
		)
		(duplicate_pad_numbers_are_jumpers no)
		(fp_line
			(start -0.299974 0.150114)
			(end -0.299974 -0.150114)
			(stroke
				(width 0.1)
				(type default)
			)
			(layer "F.Fab")
		)
		(fp_line
			(start 0.299974 0.150114)
			(end -0.299974 0.150114)
			(stroke
				(width 0.1)
				(type default)
			)
			(layer "F.Fab")
		)
		(fp_line
			(start -0.299974 -0.150114)
			(end 0.299974 -0.150114)
			(stroke
				(width 0.1)
				(type default)
			)
			(layer "F.Fab")
		)
		(fp_line
			(start 0.299974 -0.150114)
			(end 0.299974 0.150114)
			(stroke
				(width 0.1)
				(type default)
			)
			(layer "F.Fab")
		)
		(pad "1" smd rect
			(at -0.2667 0 270)
			(size 0.3048 0.381)
			(layers "F.Cu" "F.Mask" "F.Paste")
			(net "P5E_CPU1_P2_TX_BUF_C_DP<0>")
		)
		(pad "2" smd rect
			(at 0.2667 0 270)
			(size 0.3048 0.381)
			(layers "F.Cu" "F.Mask" "F.Paste")
			(net "P5E_CPU1_P2_TX_BUF_DP<0>")
		)
	)
	(footprint ""
		(layer "F.Cu")
		(at 437.875172 -29.684218 180)
		(property "Reference" "PR3839"
			(at 0 0 180)
			(layer "F.SilkS")
			(hide yes)
			(effects
				(font
					(size 1.27 1.27)
				)
			)
		)
		(property "Value" ""
			(at 0 0 180)
			(layer "F.Fab")
			(effects
				(font
					(size 1.27 1.27)
				)
			)
		)
		(duplicate_pad_numbers_are_jumpers no)
		(fp_line
			(start 0.7874 0.4064)
			(end -0.7874 0.4064)
			(stroke
				(width 0.1524)
				(type default)
			)
			(layer "F.SilkS")
		)
		(fp_line
			(start 0.7874 -0.4064)
			(end 0.7874 0.4064)
			(stroke
				(width 0.1524)
				(type default)
			)
			(layer "F.SilkS")
		)
		(fp_line
			(start -0.7874 0.4064)
			(end -0.7874 -0.4064)
			(stroke
				(width 0.1524)
				(type default)
			)
			(layer "F.SilkS")
		)
		(fp_line
			(start -0.7874 -0.4064)
			(end 0.7874 -0.4064)
			(stroke
				(width 0.1524)
				(type default)
			)
			(layer "F.SilkS")
		)
		(fp_line
			(start 0.67945 0.3048)
			(end 0.120396 0.3048)
			(stroke
				(width 0.1)
				(type default)
			)
			(layer "F.Fab")
		)
		(fp_line
			(start 0.67945 -0.3048)
			(end 0.67945 0.3048)
			(stroke
				(width 0.1)
				(type default)
			)
			(layer "F.Fab")
		)
		(fp_line
			(start 0.12065 -0.2794)
			(end 0.12065 -0.3048)
			(stroke
				(width 0.1)
				(type default)
			)
			(layer "F.Fab")
		)
		(fp_line
			(start 0.12065 -0.3048)
			(end 0.67945 -0.3048)
			(stroke
				(width 0.1)
				(type default)
			)
			(layer "F.Fab")
		)
		(fp_line
			(start 0.120396 0.3048)
			(end 0.120396 0.2794)
			(stroke
				(width 0.1)
				(type default)
			)
			(layer "F.Fab")
		)
		(fp_line
			(start 0.120396 0.2794)
			(end -0.12065 0.2794)
			(stroke
				(width 0.1)
				(type default)
			)
			(layer "F.Fab")
		)
		(fp_line
			(start -0.12065 0.3048)
			(end -0.67945 0.3048)
			(stroke
				(width 0.1)
				(type default)
			)
			(layer "F.Fab")
		)
		(fp_line
			(start -0.12065 0.2794)
			(end -0.12065 0.3048)
			(stroke
				(width 0.1)
				(type default)
			)
			(layer "F.Fab")
		)
		(fp_line
			(start -0.12065 -0.2794)
			(end 0.12065 -0.2794)
			(stroke
				(width 0.1)
				(type default)
			)
			(layer "F.Fab")
		)
		(fp_line
			(start -0.12065 -0.305054)
			(end -0.12065 -0.2794)
			(stroke
				(width 0.1)
				(type default)
			)
			(layer "F.Fab")
		)
		(fp_line
			(start -0.67945 0.3048)
			(end -0.67945 -0.305054)
			(stroke
				(width 0.1)
				(type default)
			)
			(layer "F.Fab")
		)
		(fp_line
			(start -0.67945 -0.305054)
			(end -0.12065 -0.305054)
			(stroke
				(width 0.1)
				(type default)
			)
			(layer "F.Fab")
		)
		(pad "1" smd circle
			(at -0.40005 0 180)
			(size 0 0)
			(layers "F.Cu" "F.Mask" "F.Paste")
			(net "P12V_OCP_FLTB_1")
		)
		(pad "2" smd circle
			(at 0.40005 0 180)
			(size 0 0)
			(layers "F.Cu" "F.Mask" "F.Paste")
			(net "P3V3_AUX")
		)
	)
	(footprint ""
		(layer "F.Cu")
		(at 331.793342 -392.1252)
		(property "Reference" "R1035"
			(at 0 0 0)
			(layer "F.SilkS")
			(hide yes)
			(effects
				(font
					(size 1.27 1.27)
				)
			)
		)
		(property "Value" ""
			(at 0 0 0)
			(layer "F.Fab")
			(effects
				(font
					(size 1.27 1.27)
				)
			)
		)
		(duplicate_pad_numbers_are_jumpers no)
		(fp_line
			(start -0.32512 -0.175006)
			(end 0.32512 -0.175006)
			(stroke
				(width 0.1)
				(type default)
			)
			(layer "F.Fab")
		)
		(fp_line
			(start -0.32512 0.175006)
			(end -0.32512 -0.175006)
			(stroke
				(width 0.1)
				(type default)
			)
			(layer "F.Fab")
		)
		(fp_line
			(start 0.32512 -0.175006)
			(end 0.32512 0.175006)
			(stroke
				(width 0.1)
				(type default)
			)
			(layer "F.Fab")
		)
		(fp_line
			(start 0.32512 0.175006)
			(end -0.32512 0.175006)
			(stroke
				(width 0.1)
				(type default)
			)
			(layer "F.Fab")
		)
		(pad "1" smd rect
			(at -0.2667 0)
			(size 0.3048 0.381)
			(layers "F.Cu" "F.Mask" "F.Paste")
			(net "TEST2_RT_CPU0_P1")
		)
		(pad "2" smd rect
			(at 0.2667 0 180)
			(size 0.3048 0.381)
			(layers "F.Cu" "F.Mask" "F.Paste")
			(net "GND")
		)
	)
	(footprint ""
		(layer "F.Cu")
		(at 98.344736 -120.52173 -90)
		(property "Reference" "C347"
			(at 0 0 270)
			(layer "F.SilkS")
			(hide yes)
			(effects
				(font
					(size 1.27 1.27)
				)
			)
		)
		(property "Value" ""
			(at 0 0 270)
			(layer "F.Fab")
			(effects
				(font
					(size 1.27 1.27)
				)
			)
		)
		(duplicate_pad_numbers_are_jumpers no)
		(fp_line
			(start -0.7874 0.4064)
			(end -0.7874 -0.4064)
			(stroke
				(width 0.1524)
				(type default)
			)
			(layer "F.SilkS")
		)
		(fp_line
			(start 0.7874 0.4064)
			(end -0.7874 0.4064)
			(stroke
				(width 0.1524)
				(type default)
			)
			(layer "F.SilkS")
		)
		(fp_line
			(start -0.7874 -0.4064)
			(end 0.7874 -0.4064)
			(stroke
				(width 0.1524)
				(type default)
			)
			(layer "F.SilkS")
		)
		(fp_line
			(start 0.7874 -0.4064)
			(end 0.7874 0.4064)
			(stroke
				(width 0.1524)
				(type default)
			)
			(layer "F.SilkS")
		)
		(fp_line
			(start -0.67945 0.3048)
			(end -0.67945 -0.305054)
			(stroke
				(width 0.1)
				(type default)
			)
			(layer "F.Fab")
		)
		(fp_line
			(start -0.12065 0.3048)
			(end -0.67945 0.3048)
			(stroke
				(width 0.1)
				(type default)
			)
			(layer "F.Fab")
		)
		(fp_line
			(start 0.120396 0.3048)
			(end 0.120396 0.2794)
			(stroke
				(width 0.1)
				(type default)
			)
			(layer "F.Fab")
		)
		(fp_line
			(start 0.67945 0.3048)
			(end 0.120396 0.3048)
			(stroke
				(width 0.1)
				(type default)
			)
			(layer "F.Fab")
		)
		(fp_line
			(start -0.12065 0.2794)
			(end -0.12065 0.3048)
			(stroke
				(width 0.1)
				(type default)
			)
			(layer "F.Fab")
		)
		(fp_line
			(start 0.120396 0.2794)
			(end -0.12065 0.2794)
			(stroke
				(width 0.1)
				(type default)
			)
			(layer "F.Fab")
		)
		(fp_line
			(start -0.12065 -0.2794)
			(end 0.12065 -0.2794)
			(stroke
				(width 0.1)
				(type default)
			)
			(layer "F.Fab")
		)
		(fp_line
			(start 0.12065 -0.2794)
			(end 0.12065 -0.3048)
			(stroke
				(width 0.1)
				(type default)
			)
			(layer "F.Fab")
		)
		(fp_line
			(start 0.12065 -0.3048)
			(end 0.67945 -0.3048)
			(stroke
				(width 0.1)
				(type default)
			)
			(layer "F.Fab")
		)
		(fp_line
			(start 0.67945 -0.3048)
			(end 0.67945 0.3048)
			(stroke
				(width 0.1)
				(type default)
			)
			(layer "F.Fab")
		)
		(fp_line
			(start -0.67945 -0.305054)
			(end -0.12065 -0.305054)
			(stroke
				(width 0.1)
				(type default)
			)
			(layer "F.Fab")
		)
		(fp_line
			(start -0.12065 -0.305054)
			(end -0.12065 -0.2794)
			(stroke
				(width 0.1)
				(type default)
			)
			(layer "F.Fab")
		)
		(pad "1" smd circle
			(at -0.40005 0 270)
			(size 0 0)
			(layers "F.Cu" "F.Mask" "F.Paste")
			(net "P1V8_AUX")
		)
		(pad "2" smd circle
			(at 0.40005 0 270)
			(size 0 0)
			(layers "F.Cu" "F.Mask" "F.Paste")
			(net "GND")
		)
	)
)
